(kicad_pcb
	(version 20260206)
	(generator "pcbnew")
	(generator_version "10.0")
	(general
		(thickness 1.6)
		(legacy_teardrops no)
	)
	(paper "A4")
	(title_block
		(title "Wiwynn_Tioga_Pass_MB.brd")
		(comment 1 "Tioga Pass / footprint 2031 of 4770 (J1A2), pads 124-243 of 291")
	)
	(layers
		(0 "F.Cu" signal "TOP")
		(4 "In1.Cu" signal "L2GND")
		(6 "In2.Cu" signal "L3")
		(8 "In3.Cu" signal "L4GND")
		(10 "In4.Cu" signal "L5")
		(12 "In5.Cu" signal "L6GND")
		(14 "In6.Cu" signal "L7VCC")
		(16 "In7.Cu" signal "L8VCC")
		(18 "In8.Cu" signal "L9GND")
		(20 "In9.Cu" signal "L10")
		(22 "In10.Cu" signal "L11GND")
		(24 "In11.Cu" signal "L12")
		(26 "In12.Cu" signal "L13GND")
		(2 "B.Cu" signal "BOTTOM")
		(9 "F.Adhes" user "F.Adhesive")
		(11 "B.Adhes" user "B.Adhesive")
		(13 "F.Paste" user "Package Geometry/Pastemask Top")
		(15 "B.Paste" user "Package Geometry/Pastemask Bottom")
		(5 "F.SilkS" user "Ref Des/Silkscreen Top")
		(7 "B.SilkS" user "Ref Des/Silkscreen Bottom")
		(1 "F.Mask" user "Board Geometry/Soldermask Top")
		(3 "B.Mask" user "Board Geometry/Soldermask Bottom")
		(17 "Dwgs.User" user "User.Drawings")
		(19 "Cmts.User" user "User.Comments")
		(21 "Eco1.User" user "User.Eco1")
		(23 "Eco2.User" user "User.Eco2")
		(25 "Edge.Cuts" user "Board Geometry/Outline")
		(27 "Margin" user)
		(31 "F.CrtYd" user "Package Geometry/Place Bound Top")
		(29 "B.CrtYd" user "Package Geometry/Place Bound Bottom")
		(35 "F.Fab" user "Ref Des/Assembly Top")
		(33 "B.Fab" user "Ref Des/Assembly Bottom")
	)
	(footprint ""
		(layer "F.Cu")
		(at 29.699458 -142.6718 90)
		(property "Reference" "J1A2"
			(at -2.623312 42.436542 0)
			(unlocked yes)
			(layer "F.SilkS")
			(effects
				(font
					(size 0.7874 0.5842)
					(thickness 0.1524)
				)
				(justify left)
			)
		)
		(property "Value" ""
			(at 0 0 90)
			(layer "F.Fab")
			(effects
				(font
					(size 1.27 1.27)
				)
			)
		)
		(duplicate_pad_numbers_are_jumpers no)
		(pad "121" smd rect
			(at 0 107.100116 90)
			(size 1.8034 0.508)
			(layers "F.Cu" "F.Mask" "F.Paste")
			(net "M_L_DQS_DP<15>")
		)
		(pad "122" smd rect
			(at 0 107.95 90)
			(size 1.8034 0.508)
			(layers "F.Cu" "F.Mask" "F.Paste")
			(net "M_L_DQS_DN<15>")
		)
		(pad "123" smd rect
			(at 0 108.799884 90)
			(size 1.8034 0.508)
			(layers "F.Cu" "F.Mask" "F.Paste")
			(net "GND")
		)
		(pad "124" smd rect
			(at 0 109.650022 90)
			(size 1.8034 0.508)
			(layers "F.Cu" "F.Mask" "F.Paste")
			(net "M_L_DQ<55>")
		)
		(pad "125" smd rect
			(at 0 110.499906 90)
			(size 1.8034 0.508)
			(layers "F.Cu" "F.Mask" "F.Paste")
			(net "GND")
		)
		(pad "126" smd rect
			(at 0 111.350044 90)
			(size 1.8034 0.508)
			(layers "F.Cu" "F.Mask" "F.Paste")
			(net "M_L_DQ<51>")
		)
		(pad "127" smd rect
			(at 0 112.199928 90)
			(size 1.8034 0.508)
			(layers "F.Cu" "F.Mask" "F.Paste")
			(net "GND")
		)
		(pad "128" smd rect
			(at 0 113.050066 90)
			(size 1.8034 0.508)
			(layers "F.Cu" "F.Mask" "F.Paste")
			(net "M_L_DQ<61>")
		)
		(pad "129" smd rect
			(at 0 113.89995 90)
			(size 1.8034 0.508)
			(layers "F.Cu" "F.Mask" "F.Paste")
			(net "GND")
		)
		(pad "130" smd rect
			(at 0 114.750088 90)
			(size 1.8034 0.508)
			(layers "F.Cu" "F.Mask" "F.Paste")
			(net "M_L_DQ<57>")
		)
		(pad "131" smd rect
			(at 0 115.599972 90)
			(size 1.8034 0.508)
			(layers "F.Cu" "F.Mask" "F.Paste")
			(net "GND")
		)
		(pad "132" smd rect
			(at 0 116.45011 90)
			(size 1.8034 0.508)
			(layers "F.Cu" "F.Mask" "F.Paste")
			(net "M_L_DQS_DP<16>")
		)
		(pad "133" smd rect
			(at 0 117.299994 90)
			(size 1.8034 0.508)
			(layers "F.Cu" "F.Mask" "F.Paste")
			(net "M_L_DQS_DN<16>")
		)
		(pad "134" smd rect
			(at 0 118.149878 90)
			(size 1.8034 0.508)
			(layers "F.Cu" "F.Mask" "F.Paste")
			(net "GND")
		)
		(pad "135" smd rect
			(at 0 119.000016 90)
			(size 1.8034 0.508)
			(layers "F.Cu" "F.Mask" "F.Paste")
			(net "M_L_DQ<63>")
		)
		(pad "136" smd rect
			(at 0 119.8499 90)
			(size 1.8034 0.508)
			(layers "F.Cu" "F.Mask" "F.Paste")
			(net "GND")
		)
		(pad "137" smd rect
			(at 0 120.700038 90)
			(size 1.8034 0.508)
			(layers "F.Cu" "F.Mask" "F.Paste")
			(net "M_L_DQ<59>")
		)
		(pad "138" smd rect
			(at 0 121.549922 90)
			(size 1.8034 0.508)
			(layers "F.Cu" "F.Mask" "F.Paste")
			(net "GND")
		)
		(pad "139" smd rect
			(at 0 122.40006 90)
			(size 1.8034 0.508)
			(layers "F.Cu" "F.Mask" "F.Paste")
			(net "GND")
		)
		(pad "140" smd rect
			(at 0 123.249944 90)
			(size 1.8034 0.508)
			(layers "F.Cu" "F.Mask" "F.Paste")
			(net "PVPP_KLM")
		)
		(pad "141" smd rect
			(at 0 124.100082 90)
			(size 1.8034 0.508)
			(layers "F.Cu" "F.Mask" "F.Paste")
			(net "SMB_DDR_KLM_VPP_SCL")
		)
		(pad "142" smd rect
			(at 0 124.949966 90)
			(size 1.8034 0.508)
			(layers "F.Cu" "F.Mask" "F.Paste")
			(net "PVPP_KLM")
		)
		(pad "143" smd rect
			(at 0 125.800104 90)
			(size 1.8034 0.508)
			(layers "F.Cu" "F.Mask" "F.Paste")
			(net "PVPP_KLM")
		)
		(pad "144" smd rect
			(at 0 126.649988 90)
			(size 1.8034 0.508)
			(layers "F.Cu" "F.Mask" "F.Paste")
			(net "TP_CH_L_DIMM_L0_RFU_2")
		)
		(pad "145" smd rect
			(at 4.59994 0 90)
			(size 1.8034 0.508)
			(layers "F.Cu" "F.Mask" "F.Paste")
			(net "P12V_NVDIMM_KLM")
		)
		(pad "146" smd rect
			(at 4.59994 0.849884 90)
			(size 1.8034 0.508)
			(layers "F.Cu" "F.Mask" "F.Paste")
			(net "M_L_VREF")
		)
		(pad "147" smd rect
			(at 4.59994 1.700022 90)
			(size 1.8034 0.508)
			(layers "F.Cu" "F.Mask" "F.Paste")
			(net "GND")
		)
		(pad "148" smd rect
			(at 4.59994 2.549906 90)
			(size 1.8034 0.508)
			(layers "F.Cu" "F.Mask" "F.Paste")
			(net "M_L_DQ<4>")
		)
		(pad "149" smd rect
			(at 4.59994 3.400044 90)
			(size 1.8034 0.508)
			(layers "F.Cu" "F.Mask" "F.Paste")
			(net "GND")
		)
		(pad "150" smd rect
			(at 4.59994 4.249928 90)
			(size 1.8034 0.508)
			(layers "F.Cu" "F.Mask" "F.Paste")
			(net "M_L_DQ<0>")
		)
		(pad "151" smd rect
			(at 4.59994 5.100066 90)
			(size 1.8034 0.508)
			(layers "F.Cu" "F.Mask" "F.Paste")
			(net "GND")
		)
		(pad "152" smd rect
			(at 4.59994 5.94995 90)
			(size 1.8034 0.508)
			(layers "F.Cu" "F.Mask" "F.Paste")
			(net "M_L_DQS_DN<0>")
		)
		(pad "153" smd rect
			(at 4.59994 6.800088 90)
			(size 1.8034 0.508)
			(layers "F.Cu" "F.Mask" "F.Paste")
			(net "M_L_DQS_DP<0>")
		)
		(pad "154" smd rect
			(at 4.59994 7.649972 90)
			(size 1.8034 0.508)
			(layers "F.Cu" "F.Mask" "F.Paste")
			(net "GND")
		)
		(pad "155" smd rect
			(at 4.59994 8.50011 90)
			(size 1.8034 0.508)
			(layers "F.Cu" "F.Mask" "F.Paste")
			(net "M_L_DQ<6>")
		)
		(pad "156" smd rect
			(at 4.59994 9.349994 90)
			(size 1.8034 0.508)
			(layers "F.Cu" "F.Mask" "F.Paste")
			(net "GND")
		)
		(pad "157" smd rect
			(at 4.59994 10.199878 90)
			(size 1.8034 0.508)
			(layers "F.Cu" "F.Mask" "F.Paste")
			(net "M_L_DQ<2>")
		)
		(pad "158" smd rect
			(at 4.59994 11.050016 90)
			(size 1.8034 0.508)
			(layers "F.Cu" "F.Mask" "F.Paste")
			(net "GND")
		)
		(pad "159" smd rect
			(at 4.59994 11.8999 90)
			(size 1.8034 0.508)
			(layers "F.Cu" "F.Mask" "F.Paste")
			(net "M_L_DQ<12>")
		)
		(pad "160" smd rect
			(at 4.59994 12.750038 90)
			(size 1.8034 0.508)
			(layers "F.Cu" "F.Mask" "F.Paste")
			(net "GND")
		)
		(pad "161" smd rect
			(at 4.59994 13.599922 90)
			(size 1.8034 0.508)
			(layers "F.Cu" "F.Mask" "F.Paste")
			(net "M_L_DQ<8>")
		)
		(pad "162" smd rect
			(at 4.59994 14.45006 90)
			(size 1.8034 0.508)
			(layers "F.Cu" "F.Mask" "F.Paste")
			(net "GND")
		)
		(pad "163" smd rect
			(at 4.59994 15.299944 90)
			(size 1.8034 0.508)
			(layers "F.Cu" "F.Mask" "F.Paste")
			(net "M_L_DQS_DN<1>")
		)
		(pad "164" smd rect
			(at 4.59994 16.150082 90)
			(size 1.8034 0.508)
			(layers "F.Cu" "F.Mask" "F.Paste")
			(net "M_L_DQS_DP<1>")
		)
		(pad "165" smd rect
			(at 4.59994 16.999966 90)
			(size 1.8034 0.508)
			(layers "F.Cu" "F.Mask" "F.Paste")
			(net "GND")
		)
		(pad "166" smd rect
			(at 4.59994 17.850104 90)
			(size 1.8034 0.508)
			(layers "F.Cu" "F.Mask" "F.Paste")
			(net "M_L_DQ<14>")
		)
		(pad "167" smd rect
			(at 4.59994 18.699988 90)
			(size 1.8034 0.508)
			(layers "F.Cu" "F.Mask" "F.Paste")
			(net "GND")
		)
		(pad "168" smd rect
			(at 4.59994 19.550126 90)
			(size 1.8034 0.508)
			(layers "F.Cu" "F.Mask" "F.Paste")
			(net "M_L_DQ<10>")
		)
		(pad "169" smd rect
			(at 4.59994 20.40001 90)
			(size 1.8034 0.508)
			(layers "F.Cu" "F.Mask" "F.Paste")
			(net "GND")
		)
		(pad "170" smd rect
			(at 4.59994 21.249894 90)
			(size 1.8034 0.508)
			(layers "F.Cu" "F.Mask" "F.Paste")
			(net "M_L_DQ<20>")
		)
		(pad "171" smd rect
			(at 4.59994 22.100032 90)
			(size 1.8034 0.508)
			(layers "F.Cu" "F.Mask" "F.Paste")
			(net "GND")
		)
		(pad "172" smd rect
			(at 4.59994 22.949916 90)
			(size 1.8034 0.508)
			(layers "F.Cu" "F.Mask" "F.Paste")
			(net "M_L_DQ<16>")
		)
		(pad "173" smd rect
			(at 4.59994 23.800054 90)
			(size 1.8034 0.508)
			(layers "F.Cu" "F.Mask" "F.Paste")
			(net "GND")
		)
		(pad "174" smd rect
			(at 4.59994 24.649938 90)
			(size 1.8034 0.508)
			(layers "F.Cu" "F.Mask" "F.Paste")
			(net "M_L_DQS_DN<2>")
		)
		(pad "175" smd rect
			(at 4.59994 25.500076 90)
			(size 1.8034 0.508)
			(layers "F.Cu" "F.Mask" "F.Paste")
			(net "M_L_DQS_DP<2>")
		)
		(pad "176" smd rect
			(at 4.59994 26.34996 90)
			(size 1.8034 0.508)
			(layers "F.Cu" "F.Mask" "F.Paste")
			(net "GND")
		)
		(pad "177" smd rect
			(at 4.59994 27.200098 90)
			(size 1.8034 0.508)
			(layers "F.Cu" "F.Mask" "F.Paste")
			(net "M_L_DQ<22>")
		)
		(pad "178" smd rect
			(at 4.59994 28.049982 90)
			(size 1.8034 0.508)
			(layers "F.Cu" "F.Mask" "F.Paste")
			(net "GND")
		)
		(pad "179" smd rect
			(at 4.59994 28.90012 90)
			(size 1.8034 0.508)
			(layers "F.Cu" "F.Mask" "F.Paste")
			(net "M_L_DQ<18>")
		)
		(pad "180" smd rect
			(at 4.59994 29.750004 90)
			(size 1.8034 0.508)
			(layers "F.Cu" "F.Mask" "F.Paste")
			(net "GND")
		)
		(pad "181" smd rect
			(at 4.59994 30.599888 90)
			(size 1.8034 0.508)
			(layers "F.Cu" "F.Mask" "F.Paste")
			(net "M_L_DQ<28>")
		)
		(pad "182" smd rect
			(at 4.59994 31.450026 90)
			(size 1.8034 0.508)
			(layers "F.Cu" "F.Mask" "F.Paste")
			(net "GND")
		)
		(pad "183" smd rect
			(at 4.59994 32.29991 90)
			(size 1.8034 0.508)
			(layers "F.Cu" "F.Mask" "F.Paste")
			(net "M_L_DQ<24>")
		)
		(pad "184" smd rect
			(at 4.59994 33.150048 90)
			(size 1.8034 0.508)
			(layers "F.Cu" "F.Mask" "F.Paste")
			(net "GND")
		)
		(pad "185" smd rect
			(at 4.59994 33.999932 90)
			(size 1.8034 0.508)
			(layers "F.Cu" "F.Mask" "F.Paste")
			(net "M_L_DQS_DN<3>")
		)
		(pad "186" smd rect
			(at 4.59994 34.85007 90)
			(size 1.8034 0.508)
			(layers "F.Cu" "F.Mask" "F.Paste")
			(net "M_L_DQS_DP<3>")
		)
		(pad "187" smd rect
			(at 4.59994 35.699954 90)
			(size 1.8034 0.508)
			(layers "F.Cu" "F.Mask" "F.Paste")
			(net "GND")
		)
		(pad "188" smd rect
			(at 4.59994 36.550092 90)
			(size 1.8034 0.508)
			(layers "F.Cu" "F.Mask" "F.Paste")
			(net "M_L_DQ<30>")
		)
		(pad "189" smd rect
			(at 4.59994 37.399976 90)
			(size 1.8034 0.508)
			(layers "F.Cu" "F.Mask" "F.Paste")
			(net "GND")
		)
		(pad "190" smd rect
			(at 4.59994 38.250114 90)
			(size 1.8034 0.508)
			(layers "F.Cu" "F.Mask" "F.Paste")
			(net "M_L_DQ<26>")
		)
		(pad "191" smd rect
			(at 4.59994 39.099998 90)
			(size 1.8034 0.508)
			(layers "F.Cu" "F.Mask" "F.Paste")
			(net "GND")
		)
		(pad "192" smd rect
			(at 4.59994 39.949882 90)
			(size 1.8034 0.508)
			(layers "F.Cu" "F.Mask" "F.Paste")
			(net "M_L_ECC<4>")
		)
		(pad "193" smd rect
			(at 4.59994 40.80002 90)
			(size 1.8034 0.508)
			(layers "F.Cu" "F.Mask" "F.Paste")
			(net "GND")
		)
		(pad "194" smd rect
			(at 4.59994 41.649904 90)
			(size 1.8034 0.508)
			(layers "F.Cu" "F.Mask" "F.Paste")
			(net "M_L_ECC<0>")
		)
		(pad "195" smd rect
			(at 4.59994 42.500042 90)
			(size 1.8034 0.508)
			(layers "F.Cu" "F.Mask" "F.Paste")
			(net "GND")
		)
		(pad "196" smd rect
			(at 4.59994 43.349926 90)
			(size 1.8034 0.508)
			(layers "F.Cu" "F.Mask" "F.Paste")
			(net "M_L_DQS_DN<8>")
		)
		(pad "197" smd rect
			(at 4.59994 44.200064 90)
			(size 1.8034 0.508)
			(layers "F.Cu" "F.Mask" "F.Paste")
			(net "M_L_DQS_DP<8>")
		)
		(pad "198" smd rect
			(at 4.59994 45.049948 90)
			(size 1.8034 0.508)
			(layers "F.Cu" "F.Mask" "F.Paste")
			(net "GND")
		)
		(pad "199" smd rect
			(at 4.59994 45.900086 90)
			(size 1.8034 0.508)
			(layers "F.Cu" "F.Mask" "F.Paste")
			(net "M_L_ECC<6>")
		)
		(pad "200" smd rect
			(at 4.59994 46.74997 90)
			(size 1.8034 0.508)
			(layers "F.Cu" "F.Mask" "F.Paste")
			(net "GND")
		)
		(pad "201" smd rect
			(at 4.59994 47.600108 90)
			(size 1.8034 0.508)
			(layers "F.Cu" "F.Mask" "F.Paste")
			(net "M_L_ECC<2>")
		)
		(pad "202" smd rect
			(at 4.59994 48.449992 90)
			(size 1.8034 0.508)
			(layers "F.Cu" "F.Mask" "F.Paste")
			(net "GND")
		)
		(pad "203" smd rect
			(at 4.59994 49.299876 90)
			(size 1.8034 0.508)
			(layers "F.Cu" "F.Mask" "F.Paste")
			(net "M_L_CKE<1>")
		)
		(pad "204" smd rect
			(at 4.59994 50.150014 90)
			(size 1.8034 0.508)
			(layers "F.Cu" "F.Mask" "F.Paste")
			(net "PVDDQ_KLM")
		)
		(pad "205" smd rect
			(at 4.59994 50.999898 90)
			(size 1.8034 0.508)
			(layers "F.Cu" "F.Mask" "F.Paste")
			(net "TP_CH_L_DIMM_L0_RFU_0")
		)
		(pad "206" smd rect
			(at 4.59994 51.850036 90)
			(size 1.8034 0.508)
			(layers "F.Cu" "F.Mask" "F.Paste")
			(net "PVDDQ_KLM")
		)
		(pad "207" smd rect
			(at 4.59994 52.69992 90)
			(size 1.8034 0.508)
			(layers "F.Cu" "F.Mask" "F.Paste")
			(net "M_L_BG<1>")
		)
		(pad "208" smd rect
			(at 4.59994 53.550058 90)
			(size 1.8034 0.508)
			(layers "F.Cu" "F.Mask" "F.Paste")
			(net "M_L_ALERT_N")
		)
		(pad "209" smd rect
			(at 4.59994 54.399942 90)
			(size 1.8034 0.508)
			(layers "F.Cu" "F.Mask" "F.Paste")
			(net "PVDDQ_KLM")
		)
		(pad "210" smd rect
			(at 4.59994 55.25008 90)
			(size 1.8034 0.508)
			(layers "F.Cu" "F.Mask" "F.Paste")
			(net "M_L_MA<11>")
		)
		(pad "211" smd rect
			(at 4.59994 56.099964 90)
			(size 1.8034 0.508)
			(layers "F.Cu" "F.Mask" "F.Paste")
			(net "M_L_MA<7>")
		)
		(pad "212" smd rect
			(at 4.59994 56.950102 90)
			(size 1.8034 0.508)
			(layers "F.Cu" "F.Mask" "F.Paste")
			(net "PVDDQ_KLM")
		)
		(pad "213" smd rect
			(at 4.59994 57.799986 90)
			(size 1.8034 0.508)
			(layers "F.Cu" "F.Mask" "F.Paste")
			(net "M_L_MA<5>")
		)
		(pad "214" smd rect
			(at 4.59994 58.650124 90)
			(size 1.8034 0.508)
			(layers "F.Cu" "F.Mask" "F.Paste")
			(net "M_L_MA<4>")
		)
		(pad "215" smd rect
			(at 4.59994 59.500008 90)
			(size 1.8034 0.508)
			(layers "F.Cu" "F.Mask" "F.Paste")
			(net "PVDDQ_KLM")
		)
		(pad "216" smd rect
			(at 4.59994 60.349892 90)
			(size 1.8034 0.508)
			(layers "F.Cu" "F.Mask" "F.Paste")
			(net "M_L_MA<2>")
		)
		(pad "217" smd rect
			(at 4.59994 61.20003 90)
			(size 1.8034 0.508)
			(layers "F.Cu" "F.Mask" "F.Paste")
			(net "PVDDQ_KLM")
		)
		(pad "218" smd rect
			(at 4.59994 62.049914 90)
			(size 1.8034 0.508)
			(layers "F.Cu" "F.Mask" "F.Paste")
			(net "M_L_CLK_DP<1>")
		)
		(pad "219" smd rect
			(at 4.59994 62.900052 90)
			(size 1.8034 0.508)
			(layers "F.Cu" "F.Mask" "F.Paste")
			(net "M_L_CLK_DN<1>")
		)
		(pad "220" smd rect
			(at 4.59994 63.749936 90)
			(size 1.8034 0.508)
			(layers "F.Cu" "F.Mask" "F.Paste")
			(net "PVDDQ_KLM")
		)
		(pad "221" smd rect
			(at 4.59994 64.600074 90)
			(size 1.8034 0.508)
			(layers "F.Cu" "F.Mask" "F.Paste")
			(net "PVTT_KLM")
		)
		(pad "222" smd rect
			(at 4.59994 70.550024 90)
			(size 1.8034 0.508)
			(layers "F.Cu" "F.Mask" "F.Paste")
			(net "M_L_PAR")
		)
		(pad "223" smd rect
			(at 4.59994 71.399908 90)
			(size 1.8034 0.508)
			(layers "F.Cu" "F.Mask" "F.Paste")
			(net "PVDDQ_KLM")
		)
		(pad "224" smd rect
			(at 4.59994 72.250046 90)
			(size 1.8034 0.508)
			(layers "F.Cu" "F.Mask" "F.Paste")
			(net "M_L_BA<1>")
		)
		(pad "225" smd rect
			(at 4.59994 73.09993 90)
			(size 1.8034 0.508)
			(layers "F.Cu" "F.Mask" "F.Paste")
			(net "M_L_MA<10>")
		)
		(pad "226" smd rect
			(at 4.59994 73.950068 90)
			(size 1.8034 0.508)
			(layers "F.Cu" "F.Mask" "F.Paste")
			(net "PVDDQ_KLM")
		)
		(pad "227" smd rect
			(at 4.59994 74.799952 90)
			(size 1.8034 0.508)
			(layers "F.Cu" "F.Mask" "F.Paste")
			(net "TP_CH_L_DIMM_L0_RFU_1")
		)
		(pad "228" smd rect
			(at 4.59994 75.65009 90)
			(size 1.8034 0.508)
			(layers "F.Cu" "F.Mask" "F.Paste")
			(net "M_L_MA<14>")
		)
		(pad "229" smd rect
			(at 4.59994 76.499974 90)
			(size 1.8034 0.508)
			(layers "F.Cu" "F.Mask" "F.Paste")
			(net "PVDDQ_KLM")
		)
		(pad "230" smd rect
			(at 4.59994 77.350112 90)
			(size 1.8034 0.508)
			(layers "F.Cu" "F.Mask" "F.Paste")
			(net "FM_ADR_COMPLETE_KLM_N")
		)
		(pad "231" smd rect
			(at 4.59994 78.199996 90)
			(size 1.8034 0.508)
			(layers "F.Cu" "F.Mask" "F.Paste")
			(net "PVDDQ_KLM")
		)
		(pad "232" smd rect
			(at 4.59994 79.04988 90)
			(size 1.8034 0.508)
			(layers "F.Cu" "F.Mask" "F.Paste")
			(net "M_L_MA<13>")
		)
		(pad "233" smd rect
			(at 4.59994 79.900018 90)
			(size 1.8034 0.508)
			(layers "F.Cu" "F.Mask" "F.Paste")
			(net "PVDDQ_KLM")
		)
		(pad "234" smd rect
			(at 4.59994 80.749902 90)
			(size 1.8034 0.508)
			(layers "F.Cu" "F.Mask" "F.Paste")
			(net "M_L_MA<17>")
		)
		(pad "235" smd rect
			(at 4.59994 81.60004 90)
			(size 1.8034 0.508)
			(layers "F.Cu" "F.Mask" "F.Paste")
			(net "M_L_C<2>")
		)
		(pad "236" smd rect
			(at 4.59994 82.449924 90)
			(size 1.8034 0.508)
			(layers "F.Cu" "F.Mask" "F.Paste")
			(net "PVDDQ_KLM")
		)
		(pad "237" smd rect
			(at 4.59994 83.300062 90)
			(size 1.8034 0.508)
			(layers "F.Cu" "F.Mask" "F.Paste")
			(net "M_L_CS_N<3>")
		)
		(pad "238" smd rect
			(at 4.59994 84.149946 90)
			(size 1.8034 0.508)
			(layers "F.Cu" "F.Mask" "F.Paste")
			(net "GND")
		)
		(pad "239" smd rect
			(at 4.59994 85.000084 90)
			(size 1.8034 0.508)
			(layers "F.Cu" "F.Mask" "F.Paste")
			(net "GND")
		)
		(pad "240" smd rect
			(at 4.59994 85.849968 90)
			(size 1.8034 0.508)
			(layers "F.Cu" "F.Mask" "F.Paste")
			(net "M_L_DQ<36>")
		)
	)
)
